(kicad_pcb
	(version 20241229)
	(generator "pcbnew")
	(generator_version "9.0")
	(general
		(thickness 1.294)
		(legacy_teardrops no)
	)
	(paper "A3")
	(title_block
		(title "Kintex 410T devboard")
		(date "2024-04-03")
		(rev "1.1.2")
		(comment 9 "footprints 438-442 of 975")
	)
	(layers
		(0 "F.Cu" mixed)
		(4 "In1.Cu" power)
		(6 "In2.Cu" power)
		(8 "In3.Cu" mixed)
		(10 "In4.Cu" power)
		(12 "In5.Cu" mixed)
		(14 "In6.Cu" power)
		(16 "In7.Cu" mixed)
		(18 "In8.Cu" power)
		(2 "B.Cu" mixed)
		(9 "F.Adhes" user "F.Adhesive")
		(11 "B.Adhes" user "B.Adhesive")
		(13 "F.Paste" user)
		(15 "B.Paste" user)
		(5 "F.SilkS" user "F.Silkscreen")
		(7 "B.SilkS" user "B.Silkscreen")
		(1 "F.Mask" user)
		(3 "B.Mask" user)
		(17 "Dwgs.User" user "User.Drawings")
		(19 "Cmts.User" user "User.Comments")
		(21 "Eco1.User" user "User.Eco1")
		(23 "Eco2.User" user "User.Eco2")
		(25 "Edge.Cuts" user)
		(27 "Margin" user)
		(31 "F.CrtYd" user "F.Courtyard")
		(29 "B.CrtYd" user "B.Courtyard")
		(35 "F.Fab" user)
		(33 "B.Fab" user)
	)
	(footprint "antmicro-footprints:R_0402_1005Metric"
		(layer "F.Cu")
		(at 235.915 121.5)
		(descr "Resistor SMD 0402")
		(tags "resistor SMD 0402")
		(property "Reference" "R71"
			(at 0.735 0.4 0)
			(layer "F.SilkS")
			(effects
				(font
					(size 0.7 0.7)
					(thickness 0.15)
				)
				(justify left bottom)
			)
		)
		(property "Value" "R_100R_0402"
			(at 0 1.4 0)
			(layer "F.Fab")
			(effects
				(font
					(size 0.7 0.7)
					(thickness 0.15)
				)
				(justify left bottom)
			)
		)
		(property "Description" "SMD Chip Resistor, 100 ohm, ± 1%, 62.5 mW, 0402 [1005 Metric], Thick Film, General Purpose"
			(at 0 0 0)
			(layer "F.Fab")
			(hide yes)
			(effects
				(font
					(size 1.27 1.27)
					(thickness 0.15)
				)
			)
		)
		(property "Author" "Antmicro"
			(at 0 0 0)
			(layer "F.Fab")
			(hide yes)
			(effects
				(font
					(size 1 1)
					(thickness 0.15)
				)
			)
		)
		(property "DNP" "DNP"
			(at 0 0 0)
			(layer "F.Fab")
			(hide yes)
			(effects
				(font
					(size 1 1)
					(thickness 0.15)
				)
			)
		)
		(property "License" "Apache-2.0"
			(at 0 0 0)
			(layer "F.Fab")
			(hide yes)
			(effects
				(font
					(size 1 1)
					(thickness 0.15)
				)
			)
		)
		(property "MPN" "CR0402-FX-1000GLF"
			(at 0 0 0)
			(layer "F.Fab")
			(hide yes)
			(effects
				(font
					(size 1 1)
					(thickness 0.15)
				)
			)
		)
		(property "Manufacturer" "Bourns"
			(at 0 0 0)
			(layer "F.Fab")
			(hide yes)
			(effects
				(font
					(size 1 1)
					(thickness 0.15)
				)
			)
		)
		(property "Tolerance" "1%"
			(at 0 0 0)
			(layer "F.Fab")
			(hide yes)
			(effects
				(font
					(size 1 1)
					(thickness 0.15)
				)
			)
		)
		(property "Val" "100R"
			(at 0 0 0)
			(layer "F.Fab")
			(hide yes)
			(effects
				(font
					(size 1 1)
					(thickness 0.15)
				)
			)
		)
		(property "dnp" ""
			(at 0 0 0)
			(layer "F.Fab")
			(hide yes)
			(effects
				(font
					(size 1 1)
					(thickness 0.15)
				)
			)
		)
		(property "exclude_from_bom" ""
			(at 0 0 0)
			(layer "F.Fab")
			(hide yes)
			(effects
				(font
					(size 1 1)
					(thickness 0.15)
				)
			)
		)
		(sheetname "SPI Flash + SD Card")
		(sheetfile "spi-flash.kicad_sch")
		(attr smd exclude_from_bom)
		(fp_rect
			(start -0.925 -0.47)
			(end 0.925 0.47)
			(stroke
				(width 0.05)
				(type default)
			)
			(fill no)
			(layer "F.CrtYd")
		)
		(fp_rect
			(start -0.5 -0.25)
			(end 0.5 0.25)
			(stroke
				(width 0.15)
				(type solid)
			)
			(fill no)
			(layer "F.Fab")
		)
		(pad "1" smd roundrect
			(at -0.48 0)
			(size 0.59 0.64)
			(layers "F.Cu" "F.Mask" "F.Paste")
			(roundrect_rratio 0.25)
			(net 1 "GND")
			(pintype "passive")
		)
		(pad "2" smd roundrect
			(at 0.48 0)
			(size 0.59 0.64)
			(layers "F.Cu" "F.Mask" "F.Paste")
			(roundrect_rratio 0.25)
			(net 56 "/FPGA Bank 14 & 15/SYSTEM_FLASH.CLK")
			(pintype "passive")
		)
	)
	(footprint "antmicro-footprints:R_0402_1005Metric"
		(layer "F.Cu")
		(at 225.1 112.2)
		(descr "Resistor SMD 0402")
		(tags "resistor SMD 0402")
		(property "Reference" "R99"
			(at -3.65 0.4 0)
			(layer "F.SilkS")
			(effects
				(font
					(size 0.7 0.7)
					(thickness 0.15)
				)
				(justify left bottom)
			)
		)
		(property "Value" "R_0R_0402"
			(at 0 1.4 0)
			(layer "F.Fab")
			(effects
				(font
					(size 0.7 0.7)
					(thickness 0.15)
				)
				(justify left bottom)
			)
		)
		(property "Description" "SMD Chip Resistor, Jumper, 0 ohm, 100 mW, 0402 [1005 Metric], Thick Film, General Purpose"
			(at 0 0 0)
			(layer "F.Fab")
			(hide yes)
			(effects
				(font
					(size 1.27 1.27)
					(thickness 0.15)
				)
			)
		)
		(property "Author" "Antmicro"
			(at 0 0 0)
			(layer "F.Fab")
			(hide yes)
			(effects
				(font
					(size 1 1)
					(thickness 0.15)
				)
			)
		)
		(property "Current" "1A"
			(at 0 0 0)
			(layer "F.Fab")
			(hide yes)
			(effects
				(font
					(size 1 1)
					(thickness 0.15)
				)
			)
		)
		(property "License" "Apache-2.0"
			(at 0 0 0)
			(layer "F.Fab")
			(hide yes)
			(effects
				(font
					(size 1 1)
					(thickness 0.15)
				)
			)
		)
		(property "MPN" "ERJ2GE0R00X"
			(at 0 0 0)
			(layer "F.Fab")
			(hide yes)
			(effects
				(font
					(size 1 1)
					(thickness 0.15)
				)
			)
		)
		(property "Manufacturer" "Panasonic"
			(at 0 0 0)
			(layer "F.Fab")
			(hide yes)
			(effects
				(font
					(size 1 1)
					(thickness 0.15)
				)
			)
		)
		(property "Tolerance" ""
			(at 0 0 0)
			(layer "F.Fab")
			(hide yes)
			(effects
				(font
					(size 1 1)
					(thickness 0.15)
				)
			)
		)
		(property "Val" "0R"
			(at 0 0 0)
			(layer "F.Fab")
			(hide yes)
			(effects
				(font
					(size 1 1)
					(thickness 0.15)
				)
			)
		)
		(sheetname "SPI Flash + SD Card")
		(sheetfile "spi-flash.kicad_sch")
		(attr smd)
		(fp_rect
			(start -0.925 -0.47)
			(end 0.925 0.47)
			(stroke
				(width 0.05)
				(type default)
			)
			(fill no)
			(layer "F.CrtYd")
		)
		(fp_rect
			(start -0.5 -0.25)
			(end 0.5 0.25)
			(stroke
				(width 0.15)
				(type solid)
			)
			(fill no)
			(layer "F.Fab")
		)
		(pad "1" smd roundrect
			(at -0.48 0)
			(size 0.59 0.64)
			(layers "F.Cu" "F.Mask" "F.Paste")
			(roundrect_rratio 0.25)
			(net 420 "/FPGA Bank 16 & 17/USR_FLASH_1.~{CS}")
			(pintype "passive")
		)
		(pad "2" smd roundrect
			(at 0.48 0)
			(size 0.59 0.64)
			(layers "F.Cu" "F.Mask" "F.Paste")
			(roundrect_rratio 0.25)
			(net 906 "/SPI Flash + SD Card/USR_FLASH_1_~{CS}")
			(pintype "passive")
		)
	)
	(footprint "antmicro-footprints:C_0402_1005Metric"
		(layer "F.Cu")
		(at 232.6 137.1)
		(descr "Capacitor SMD 0402")
		(tags "capacitor SMD 0402")
		(property "Reference" "C367"
			(at -1.35 -0.55 0)
			(layer "F.SilkS")
			(effects
				(font
					(size 0.7 0.7)
					(thickness 0.15)
				)
				(justify left bottom)
			)
		)
		(property "Value" "C_22p_0402"
			(at 0 1.4 0)
			(layer "F.Fab")
			(effects
				(font
					(size 0.7 0.7)
					(thickness 0.15)
				)
				(justify left bottom)
			)
		)
		(property "Description" "SMD Multilayer Ceramic Capacitor, 22 pF, 50 V, 0402 [1005 Metric], ± 5%, C0G / NP0, CC Series"
			(at 0 0 0)
			(layer "F.Fab")
			(hide yes)
			(effects
				(font
					(size 1.27 1.27)
					(thickness 0.15)
				)
			)
		)
		(property "Author" "Antmicro"
			(at 0 0 0)
			(layer "F.Fab")
			(hide yes)
			(effects
				(font
					(size 1 1)
					(thickness 0.15)
				)
			)
		)
		(property "Dielectric" ""
			(at 0 0 0)
			(layer "F.Fab")
			(hide yes)
			(effects
				(font
					(size 1 1)
					(thickness 0.15)
				)
			)
		)
		(property "License" "Apache-2.0"
			(at 0 0 0)
			(layer "F.Fab")
			(hide yes)
			(effects
				(font
					(size 1 1)
					(thickness 0.15)
				)
			)
		)
		(property "MPN" "CC0402JRNPO9BN220"
			(at 0 0 0)
			(layer "F.Fab")
			(hide yes)
			(effects
				(font
					(size 1 1)
					(thickness 0.15)
				)
			)
		)
		(property "Manufacturer" "YAGEO"
			(at 0 0 0)
			(layer "F.Fab")
			(hide yes)
			(effects
				(font
					(size 1 1)
					(thickness 0.15)
				)
			)
		)
		(property "Val" "22p"
			(at 0 0 0)
			(layer "F.Fab")
			(hide yes)
			(effects
				(font
					(size 1 1)
					(thickness 0.15)
				)
			)
		)
		(property "Voltage" ""
			(at 0 0 0)
			(layer "F.Fab")
			(hide yes)
			(effects
				(font
					(size 1 1)
					(thickness 0.15)
				)
			)
		)
		(sheetname "Clocks")
		(sheetfile "clocks.kicad_sch")
		(attr smd)
		(fp_rect
			(start -0.925 -0.47)
			(end 0.925 0.47)
			(stroke
				(width 0.05)
				(type default)
			)
			(fill no)
			(layer "F.CrtYd")
		)
		(fp_line
			(start -0.494 -0.25)
			(end 0.504 -0.25)
			(stroke
				(width 0.15)
				(type solid)
			)
			(layer "F.Fab")
		)
		(fp_line
			(start -0.494 0.248)
			(end -0.494 -0.25)
			(stroke
				(width 0.15)
				(type solid)
			)
			(layer "F.Fab")
		)
		(fp_line
			(start 0.504 -0.25)
			(end 0.504 0.248)
			(stroke
				(width 0.15)
				(type solid)
			)
			(layer "F.Fab")
		)
		(fp_line
			(start 0.504 0.248)
			(end -0.494 0.248)
			(stroke
				(width 0.15)
				(type solid)
			)
			(layer "F.Fab")
		)
		(pad "1" smd roundrect
			(at -0.48 0)
			(size 0.59 0.64)
			(layers "F.Cu" "F.Mask" "F.Paste")
			(roundrect_rratio 0.25)
			(net 1 "GND")
			(pintype "passive")
		)
		(pad "2" smd roundrect
			(at 0.48 0)
			(size 0.59 0.64)
			(layers "F.Cu" "F.Mask" "F.Paste")
			(roundrect_rratio 0.25)
			(net 753 "/Clocks/PLL_XO")
			(pintype "passive")
		)
	)
	(footprint "antmicro-footprints:C_2220_5650Metric"
		(layer "F.Cu")
		(at 246.475 185.575 90)
		(descr "Capacitor SMD 2220")
		(tags "capacitor SMD 2220")
		(property "Reference" "C197"
			(at 3.675 -1.425 180)
			(layer "F.SilkS")
			(effects
				(font
					(size 0.7 0.7)
					(thickness 0.15)
				)
				(justify left bottom)
			)
		)
		(property "Value" "C_22u_100V_2220"
			(at 0 3.9 90)
			(layer "F.Fab")
			(effects
				(font
					(size 0.7 0.7)
					(thickness 0.15)
				)
				(justify left bottom)
			)
		)
		(property "Description" "SMT Multilayer Ceramic Capacitor, 22 µF, 100 V, 2220 [5750 Metric], ± 20%, X7S, C"
			(at 0 0 90)
			(layer "F.Fab")
			(hide yes)
			(effects
				(font
					(size 1.27 1.27)
					(thickness 0.15)
				)
			)
		)
		(property "Author" "Antmicro"
			(at 432.05 -60.9 0)
			(layer "F.Fab")
			(hide yes)
			(effects
				(font
					(size 1 1)
					(thickness 0.15)
				)
			)
		)
		(property "Dielectric" "X7S"
			(at 432.05 -60.9 0)
			(layer "F.Fab")
			(hide yes)
			(effects
				(font
					(size 1 1)
					(thickness 0.15)
				)
			)
		)
		(property "License" "Apache-2.0"
			(at 432.05 -60.9 0)
			(layer "F.Fab")
			(hide yes)
			(effects
				(font
					(size 1 1)
					(thickness 0.15)
				)
			)
		)
		(property "MPN" "C5750X7S2A226M280KB"
			(at 432.05 -60.9 0)
			(layer "F.Fab")
			(hide yes)
			(effects
				(font
					(size 1 1)
					(thickness 0.15)
				)
			)
		)
		(property "Manufacturer" "TDK"
			(at 432.05 -60.9 0)
			(layer "F.Fab")
			(hide yes)
			(effects
				(font
					(size 1 1)
					(thickness 0.15)
				)
			)
		)
		(property "Val" "22u"
			(at 432.05 -60.9 0)
			(layer "F.Fab")
			(hide yes)
			(effects
				(font
					(size 1 1)
					(thickness 0.15)
				)
			)
		)
		(property "Voltage" "100V"
			(at 432.05 -60.9 0)
			(layer "F.Fab")
			(hide yes)
			(effects
				(font
					(size 1 1)
					(thickness 0.15)
				)
			)
		)
		(sheetname "Power supply")
		(sheetfile "power-supply.kicad_sch")
		(attr smd)
		(fp_line
			(start -1.415 -2.61)
			(end 1.415 -2.61)
			(stroke
				(width 0.15)
				(type solid)
			)
			(layer "F.SilkS")
		)
		(fp_line
			(start -1.415 2.61)
			(end 1.415 2.61)
			(stroke
				(width 0.15)
				(type solid)
			)
			(layer "F.SilkS")
		)
		(fp_rect
			(start -3.7 -2.95)
			(end 3.7 2.95)
			(stroke
				(width 0.05)
				(type solid)
			)
			(fill no)
			(layer "F.CrtYd")
		)
		(fp_rect
			(start -2.85 -2.5)
			(end 2.85 2.5)
			(stroke
				(width 0.15)
				(type solid)
			)
			(fill no)
			(layer "F.Fab")
		)
		(pad "1" smd roundrect
			(at -2.55 0 90)
			(size 1.8 5.4)
			(layers "F.Cu" "F.Mask" "F.Paste")
			(roundrect_rratio 0.138889)
			(net 699 "GNDD")
			(pintype "passive")
		)
		(pad "2" smd roundrect
			(at 2.55 0 90)
			(size 1.8 5.4)
			(layers "F.Cu" "F.Mask" "F.Paste")
			(roundrect_rratio 0.138889)
			(net 698 "/Power supply/VDD")
			(pintype "passive")
		)
	)
	(footprint "antmicro-footprints:C_0603_1608Metric"
		(layer "F.Cu")
		(at 195.6 156.849)
		(descr "Capacitor SMD 0603")
		(tags "capacitor 0603")
		(property "Reference" "C357"
			(at -3.89 0.401 0)
			(layer "F.SilkS")
			(effects
				(font
					(size 0.7 0.7)
					(thickness 0.15)
				)
				(justify left bottom)
			)
		)
		(property "Value" "C_22u_0603"
			(at 0 1.6 0)
			(layer "F.Fab")
			(effects
				(font
					(size 0.7 0.7)
					(thickness 0.15)
				)
				(justify left bottom)
			)
		)
		(property "Description" "SMD Multilayer Ceramic Capacitor, 22 µF, 6.3 V, 0603 [1608 Metric], ± 20%, X5R, GRM Series"
			(at 0 0 0)
			(layer "F.Fab")
			(hide yes)
			(effects
				(font
					(size 1.27 1.27)
					(thickness 0.15)
				)
			)
		)
		(property "Author" "Antmicro"
			(at 0 0 0)
			(layer "F.Fab")
			(hide yes)
			(effects
				(font
					(size 1 1)
					(thickness 0.15)
				)
			)
		)
		(property "Dielectric" ""
			(at 0 0 0)
			(layer "F.Fab")
			(hide yes)
			(effects
				(font
					(size 1 1)
					(thickness 0.15)
				)
			)
		)
		(property "License" "Apache-2.0"
			(at 0 0 0)
			(layer "F.Fab")
			(hide yes)
			(effects
				(font
					(size 1 1)
					(thickness 0.15)
				)
			)
		)
		(property "MPN" "GRM188R60J226MEA0D"
			(at 0 0 0)
			(layer "F.Fab")
			(hide yes)
			(effects
				(font
					(size 1 1)
					(thickness 0.15)
				)
			)
		)
		(property "Manufacturer" "Murata"
			(at 0 0 0)
			(layer "F.Fab")
			(hide yes)
			(effects
				(font
					(size 1 1)
					(thickness 0.15)
				)
			)
		)
		(property "Val" "22u"
			(at 0 0 0)
			(layer "F.Fab")
			(hide yes)
			(effects
				(font
					(size 1 1)
					(thickness 0.15)
				)
			)
		)
		(property "Voltage" ""
			(at 0 0 0)
			(layer "F.Fab")
			(hide yes)
			(effects
				(font
					(size 1 1)
					(thickness 0.15)
				)
			)
		)
		(sheetname "DC-DC Converters")
		(sheetfile "dc-dc.kicad_sch")
		(attr smd)
		(fp_line
			(start -0.15 -0.4)
			(end 0.15 -0.4)
			(stroke
				(width 0.15)
				(type solid)
			)
			(layer "F.SilkS")
		)
		(fp_line
			(start -0.15 0.4)
			(end 0.15 0.4)
			(stroke
				(width 0.15)
				(type solid)
			)
			(layer "F.SilkS")
		)
		(fp_rect
			(start -1.25 -0.65)
			(end 1.25 0.65)
			(stroke
				(width 0.05)
				(type solid)
			)
			(fill no)
			(layer "F.CrtYd")
		)
		(fp_rect
			(start -0.8 -0.4)
			(end 0.8 0.4)
			(stroke
				(width 0.15)
				(type solid)
			)
			(fill no)
			(layer "F.Fab")
		)
		(pad "1" smd roundrect
			(at -0.7 0)
			(size 0.8 1)
			(layers "F.Cu" "F.Mask" "F.Paste")
			(roundrect_rratio 0.2)
			(net 1 "GND")
			(pintype "passive")
		)
		(pad "2" smd roundrect
			(at 0.7 0)
			(size 0.8 1)
			(layers "F.Cu" "F.Mask" "F.Paste")
			(roundrect_rratio 0.2)
			(net 751 "/DC-DC Converters/1V0_REG")
			(pintype "passive")
		)
	)
)
